# BASEBOARD_FAB2 (Tioga Pass) — schematic netlist excerpt (pin names and nets, part order shuffled) for the footprints in the layout excerpt that follows; sources: Cadence DE-HDL packaged netlist, KiCad conversion of Wiwynn_Tioga_Pass_MB.brd

R9W1  RES  10.0K 1% CHIP  pkg 0402  page 186 : A = P3V3_STBY ; B = FM_MEZZA_PRSNT1_N
R25W73  RES  33.2 1% CHIP  pkg 0402  page 146 : A = IRQ_LPC_SERIRQ_N ; B = IRQ_LPC_SERIRQ_R
C5T4  CAP_A  47UF 4V 20% X5R  pkg 0603V  page 217 : A = PVDDQ_ABC ; B = GND

(kicad_pcb
	(version 20260206)
	(generator "pcbnew")
	(generator_version "10.0")
	(general
		(thickness 1.6)
		(legacy_teardrops no)
	)
	(paper "A4")
	(title_block
		(title "Wiwynn_Tioga_Pass_MB.brd")
		(comment 1 "Tioga Pass / footprints 2664-2666 of 4770")
	)
	(layers
		(0 "F.Cu" signal "TOP")
		(4 "In1.Cu" signal "L2GND")
		(6 "In2.Cu" signal "L3")
		(8 "In3.Cu" signal "L4GND")
		(10 "In4.Cu" signal "L5")
		(12 "In5.Cu" signal "L6GND")
		(14 "In6.Cu" signal "L7VCC")
		(16 "In7.Cu" signal "L8VCC")
		(18 "In8.Cu" signal "L9GND")
		(20 "In9.Cu" signal "L10")
		(22 "In10.Cu" signal "L11GND")
		(24 "In11.Cu" signal "L12")
		(26 "In12.Cu" signal "L13GND")
		(2 "B.Cu" signal "BOTTOM")
		(9 "F.Adhes" user "F.Adhesive")
		(11 "B.Adhes" user "B.Adhesive")
		(13 "F.Paste" user "Package Geometry/Pastemask Top")
		(15 "B.Paste" user "Package Geometry/Pastemask Bottom")
		(5 "F.SilkS" user "Ref Des/Silkscreen Top")
		(7 "B.SilkS" user "Ref Des/Silkscreen Bottom")
		(1 "F.Mask" user "Board Geometry/Soldermask Top")
		(3 "B.Mask" user "Board Geometry/Soldermask Bottom")
		(17 "Dwgs.User" user "User.Drawings")
		(19 "Cmts.User" user "User.Comments")
		(21 "Eco1.User" user "User.Eco1")
		(23 "Eco2.User" user "User.Eco2")
		(25 "Edge.Cuts" user "Board Geometry/Outline")
		(27 "Margin" user)
		(31 "F.CrtYd" user "Package Geometry/Place Bound Top")
		(29 "B.CrtYd" user "Package Geometry/Place Bound Bottom")
		(35 "F.Fab" user "Ref Des/Assembly Top")
		(33 "B.Fab" user "Ref Des/Assembly Bottom")
	)
	(footprint ""
		(layer "B.Cu")
		(at 411.21076 -45.53712)
		(property "Reference" "R25W73"
			(at 0.8382 -0.67818 0)
			(unlocked yes)
			(layer "B.SilkS")
			(effects
				(font
					(size 0.4064 0.254)
					(thickness 0.1524)
				)
				(justify left mirror)
			)
		)
		(property "Value" ""
			(at 0 0 0)
			(layer "B.Fab")
			(effects
				(font
					(size 1.27 1.27)
				)
				(justify mirror)
			)
		)
		(duplicate_pad_numbers_are_jumpers no)
		(fp_poly
			(pts
				(xy 0.2794 -0.1016) (xy -0.2794 -0.1016) (xy -0.2794 0.9906) (xy 0.2794 0.9906)
			)
			(stroke
				(width 0)
				(type default)
			)
			(fill no)
			(layer "B.CrtYd")
		)
		(fp_line
			(start -0.2794 -0.1016)
			(end 0.2794 -0.1016)
			(stroke
				(width 0.1)
				(type default)
			)
			(layer "B.Fab")
		)
		(fp_line
			(start -0.2794 0.9906)
			(end -0.2794 -0.1016)
			(stroke
				(width 0.1)
				(type default)
			)
			(layer "B.Fab")
		)
		(fp_line
			(start 0.2794 -0.1016)
			(end 0.2794 0.9906)
			(stroke
				(width 0.1)
				(type default)
			)
			(layer "B.Fab")
		)
		(fp_line
			(start 0.2794 0.9906)
			(end -0.2794 0.9906)
			(stroke
				(width 0.1)
				(type default)
			)
			(layer "B.Fab")
		)
		(pad "1" smd rect
			(at 0 0 180)
			(size 0.508 0.508)
			(layers "B.Cu" "B.Mask" "B.Paste")
			(net "IRQ_LPC_SERIRQ_N")
		)
		(pad "2" smd rect
			(at 0 0.889 180)
			(size 0.508 0.508)
			(layers "B.Cu" "B.Mask" "B.Paste")
			(net "IRQ_LPC_SERIRQ_R")
		)
		(zone
			(layer "B.Cu")
			(hatch none 0.5)
			(connect_pads
				(clearance 0)
			)
			(min_thickness 0.25)
			(keepout
				(tracks allowed)
				(vias not_allowed)
				(pads allowed)
				(copperpour not_allowed)
				(footprints allowed)
			)
			(placement
				(enabled no)
				(sheetname "")
			)
			(fill
				(thermal_gap 0.5)
				(thermal_bridge_width 0.5)
				(island_removal_mode 0)
			)
			(polygon
				(pts
					(xy 411.46476 -45.28312) (xy 410.95676 -45.28312) (xy 410.95676 -44.90212) (xy 411.46476 -44.90212)
				)
			)
		)
		(zone
			(layer "B.Cu")
			(hatch none 0.5)
			(connect_pads
				(clearance 0)
			)
			(min_thickness 0.25)
			(keepout
				(tracks not_allowed)
				(vias allowed)
				(pads allowed)
				(copperpour not_allowed)
				(footprints allowed)
			)
			(placement
				(enabled no)
				(sheetname "")
			)
			(fill
				(thermal_gap 0.5)
				(thermal_bridge_width 0.5)
				(island_removal_mode 0)
			)
			(polygon
				(pts
					(xy 411.46476 -44.90212) (xy 410.95676 -44.90212) (xy 410.95676 -45.28312) (xy 411.46476 -45.28312)
				)
			)
		)
	)
	(footprint ""
		(layer "B.Cu")
		(at 491.4392 -115.3668 180)
		(property "Reference" "R9W1"
			(at 0.8382 -0.67818 180)
			(unlocked yes)
			(layer "B.SilkS")
			(effects
				(font
					(size 0.4064 0.254)
					(thickness 0.1524)
				)
				(justify left mirror)
			)
		)
		(property "Value" ""
			(at 0 0 0)
			(layer "B.Fab")
			(effects
				(font
					(size 1.27 1.27)
				)
				(justify mirror)
			)
		)
		(duplicate_pad_numbers_are_jumpers no)
		(fp_poly
			(pts
				(xy 0.2794 -0.1016) (xy -0.2794 -0.1016) (xy -0.2794 0.9906) (xy 0.2794 0.9906)
			)
			(stroke
				(width 0)
				(type default)
			)
			(fill no)
			(layer "B.CrtYd")
		)
		(fp_line
			(start 0.2794 0.9906)
			(end -0.2794 0.9906)
			(stroke
				(width 0.1)
				(type default)
			)
			(layer "B.Fab")
		)
		(fp_line
			(start 0.2794 -0.1016)
			(end 0.2794 0.9906)
			(stroke
				(width 0.1)
				(type default)
			)
			(layer "B.Fab")
		)
		(fp_line
			(start -0.2794 0.9906)
			(end -0.2794 -0.1016)
			(stroke
				(width 0.1)
				(type default)
			)
			(layer "B.Fab")
		)
		(fp_line
			(start -0.2794 -0.1016)
			(end 0.2794 -0.1016)
			(stroke
				(width 0.1)
				(type default)
			)
			(layer "B.Fab")
		)
		(pad "1" smd rect
			(at 0 0)
			(size 0.508 0.508)
			(layers "B.Cu" "B.Mask" "B.Paste")
			(net "P3V3_STBY")
		)
		(pad "2" smd rect
			(at 0 0.889)
			(size 0.508 0.508)
			(layers "B.Cu" "B.Mask" "B.Paste")
			(net "FM_MEZZA_PRSNT1_N")
		)
		(zone
			(layer "B.Cu")
			(hatch none 0.5)
			(connect_pads
				(clearance 0)
			)
			(min_thickness 0.25)
			(keepout
				(tracks not_allowed)
				(vias allowed)
				(pads allowed)
				(copperpour not_allowed)
				(footprints allowed)
			)
			(placement
				(enabled no)
				(sheetname "")
			)
			(fill
				(thermal_gap 0.5)
				(thermal_bridge_width 0.5)
				(island_removal_mode 0)
			)
			(polygon
				(pts
					(xy 491.1852 -116.0018) (xy 491.6932 -116.0018) (xy 491.6932 -115.6208) (xy 491.1852 -115.6208)
				)
			)
		)
		(zone
			(layer "B.Cu")
			(hatch none 0.5)
			(connect_pads
				(clearance 0)
			)
			(min_thickness 0.25)
			(keepout
				(tracks allowed)
				(vias not_allowed)
				(pads allowed)
				(copperpour not_allowed)
				(footprints allowed)
			)
			(placement
				(enabled no)
				(sheetname "")
			)
			(fill
				(thermal_gap 0.5)
				(thermal_bridge_width 0.5)
				(island_removal_mode 0)
			)
			(polygon
				(pts
					(xy 491.1852 -115.6208) (xy 491.6932 -115.6208) (xy 491.6932 -116.0018) (xy 491.1852 -116.0018)
				)
			)
		)
	)
	(footprint ""
		(layer "B.Cu")
		(at 276.7076 -28.2956 90)
		(property "Reference" "C5T4"
			(at 0 0 90)
			(layer "B.SilkS")
			(hide yes)
			(effects
				(font
					(size 1.27 1.27)
				)
				(justify mirror)
			)
		)
		(property "Value" ""
			(at 0 0 90)
			(layer "B.Fab")
			(effects
				(font
					(size 1.27 1.27)
				)
				(justify mirror)
			)
		)
		(duplicate_pad_numbers_are_jumpers no)
		(fp_rect
			(start 0.500126 1.598422)
			(end -0.500126 -0.201422)
			(stroke
				(width 0)
				(type default)
			)
			(fill no)
			(layer "B.CrtYd")
		)
		(fp_line
			(start 0.500126 -0.201422)
			(end -0.500126 -0.201422)
			(stroke
				(width 0.1)
				(type default)
			)
			(layer "B.Fab")
		)
		(fp_line
			(start -0.500126 -0.201422)
			(end -0.500126 1.598422)
			(stroke
				(width 0.1)
				(type default)
			)
			(layer "B.Fab")
		)
		(fp_line
			(start 0.500126 1.598422)
			(end 0.500126 -0.201422)
			(stroke
				(width 0.1)
				(type default)
			)
			(layer "B.Fab")
		)
		(fp_line
			(start -0.500126 1.598422)
			(end 0.500126 1.598422)
			(stroke
				(width 0.1)
				(type default)
			)
			(layer "B.Fab")
		)
		(pad "1" smd rect
			(at 0 0)
			(size 0.889 0.9906)
			(layers "B.Cu" "B.Mask" "B.Paste")
			(net "PVDDQ_ABC")
		)
		(pad "2" smd rect
			(at 0 1.397)
			(size 0.889 0.9906)
			(layers "B.Cu" "B.Mask" "B.Paste")
			(net "GND")
		)
		(zone
			(layer "B.Cu")
			(hatch none 0.5)
			(connect_pads
				(clearance 0)
			)
			(min_thickness 0.25)
			(keepout
				(tracks allowed)
				(vias not_allowed)
				(pads allowed)
				(copperpour not_allowed)
				(footprints allowed)
			)
			(placement
				(enabled no)
				(sheetname "")
			)
			(fill
				(thermal_gap 0.5)
				(thermal_bridge_width 0.5)
				(island_removal_mode 0)
			)
			(polygon
				(pts
					(xy 277.6601 -28.7909) (xy 277.1521 -28.7909) (xy 277.1521 -27.8003) (xy 277.6601 -27.8003)
				)
			)
		)
		(zone
			(layer "B.Cu")
			(hatch none 0.5)
			(connect_pads
				(clearance 0)
			)
			(min_thickness 0.25)
			(keepout
				(tracks not_allowed)
				(vias allowed)
				(pads allowed)
				(copperpour not_allowed)
				(footprints allowed)
			)
			(placement
				(enabled no)
				(sheetname "")
			)
			(fill
				(thermal_gap 0.5)
				(thermal_bridge_width 0.5)
				(island_removal_mode 0)
			)
			(polygon
				(pts
					(xy 277.6601 -28.7909) (xy 277.1521 -28.7909) (xy 277.1521 -27.8003) (xy 277.6601 -27.8003)
				)
			)
		)
	)
)
